FILE_TYPE = CONNECTIVITY;
{Allegro Design Entry HDL 17.2-2016 S081 (4005846) 1/11/2022}
"PAGE_NUMBER" = 194;
0"NC";
1"P3V3_AUX\g";
2"P3V3_AUX\g";
3"P3V3_AUX\g";
4"P3V3_AUX\g";
5"P3V3_AUX\g";
6"GND\g";
7"GND\g";
8"GND\g";
9"GND\g";
10"GND\g";
11"GND\g";
12"GND\g";
13"GND\g";
14"GND\g";
15"GND\g";
16"GND\g";
17"GND\g";
18"GND\g";
19"GND\g";
20"GND\g";
21"GND\g";
22"GND\g";
23"GND\g";
24"USB2_HOST_PCH_0_DN";
25"USB2_HUB_2_BUF_EXT_R_DN";
26"USB2_HUB_2_BUF_EXT_R_DP";
27"USB2_HOST_PCH_0_DP";
28"USB2_HUB_2_EXT_DP";
29"USB_HUB_2_PSELF";
30"PD_USB_HUB_2_VREG";
31"PD_USB_HUB_2_RSTN";
32"RST_USB_HUB_2_R_N";
33"RST_USB_HUB_N";
34"USB_HUB_2_RREF";
35"NC_USB_HUB_2_DP3";
36"NC_USB_HUB_2_DM2";
37"NC_USB_HUB_2_DP2";
38"USB2_HUB_2_EXT_DN";
39"USB_HUB_2_XTAL_OUT";
40"USB_HUB_2_XTAL_IN";
41"USB2_0_DP";
42"USB2_0_DN";
43"NC_USB_HUB_2_DP4";
44"USB_HUB_2_DVDD";
45"P3V3_AUX_USB_HUB_2";
46"USB2_PCH_0_R_DN";
47"USB_HUB_2_OVCUR3";
48"USB_HUB_2_OVCUR4";
49"USB2_HUB_2_EXT_DP";
50"USB2_PCH_0_R_DP";
51"USB_HUB_2_PGANG";
52"USB_HUB_2_OVCUR1";
53"USB_HUB_2_OVCUR3";
54"USB_HUB_2_OVCUR4";
55"TP_USB_HUB_2_ENA_HS";
56"USB2_HUB_2_BUF_EXT_R_DN";
57"USB_HUB_2_TEST";
58"NC_USB_HUB_2_SDA";
59"USB_HUB_2_OVCUR2";
60"USB2_HUB_2_BUF_EXT_DP";
61"USB2_HUB_2_BUF_EXT_R_DP";
62"USB2_HUB_2_BUF_EXT_DN";
63"PD_USB_HUB_2_EQ";
64"USB_HUB_2_OVCUR1";
65"USB_HUB_2_OVCUR2";
66"TP_USB_HUB_2_CD";
67"TP_USB_HUB_2_TEST";
68"USB2_HUB_2_EXT_DN";
69"NC_USB_HUB_2_DM4";
70"NC_USB_HUB_2_DM3";
71"USB_HUB_2_PSELF";
%"UNIVERSAL_GND"
"1","(-500,-2900)","0","logical_power","I1";
;
CDS_LIB"logical_power"
HDL_POWER"GND";
"A"8;
%"UNIVERSAL_POWER"
"1","(-3500,1025)","2","logical_power","I10";
;
HDL_POWER"P3V3_AUX"
CDS_LIB"logical_power";
"A"1;
%"Q_RES"
"1","(-2075,975)","0","pure_quanta","I13";
;
PART_NUMBER"CS03322FB03"
MATERIAL"EMPTY"
PACK_TYPE"0402LF"
TOLERANCE"1%"
WATTAGE"1/16W"
VALUE"33.2"
$LOCATION"R4451"
CDS_LIB"pure_quanta"
CDS_LOCATION"R4451"
$SEC"1"
CDS_SEC"1";
"B"
$PN"2"32;
"A"
$PN"1"33;
%"UNIVERSAL_GND"
"1","(-1625,400)","0","logical_power","I14";
;
CDS_LIB"logical_power"
HDL_POWER"GND";
"A"11;
%"Q_CAP"
"1","(-1625,700)","0","pure_quanta","I15";
;
PART_NUMBER"CH5104KEB02"
VALUE"1UF"
VOLTAGE"25V"
TOLERANCE"10%"
MATERIAL"EMPTY"
PACK_TYPE"C0402"
$LOCATION"C2317"
CDS_LIB"pure_quanta"
CDS_LOCATION"C2317"
$SEC"1"
CDS_SEC"1";
"B"
$PN"2"11;
"A"
$PN"1"32;
%"Q_RES"
"1","(-1550,-2275)","0","pure_quanta","I16";
;
PART_NUMBER"CS00002JB13"
PACK_TYPE"0402LF"
VALUE"0"
MATERIAL"EMPTY"
$LOCATION"R4455"
CDS_LIB"pure_quanta"
WATTAGE"1/16W"
TOLERANCE"5%"
CDS_LOCATION"R4455"
$SEC"1"
CDS_SEC"1";
"B"
$PN"2"25;
"A"
$PN"1"68;
%"Q_RES"
"1","(-1550,-2225)","0","pure_quanta","I17";
;
PART_NUMBER"CS00002JB13"
MATERIAL"EMPTY"
VALUE"0"
PACK_TYPE"0402LF"
$LOCATION"R4454"
CDS_LIB"pure_quanta"
WATTAGE"1/16W"
TOLERANCE"5%"
CDS_LOCATION"R4454"
$SEC"1"
CDS_SEC"1";
"B"
$PN"2"26;
"A"
$PN"1"28;
%"Q_RES"
"2","(-1350,-2100)","0","pure_quanta","I18";
;
PART_NUMBER"CS00002JB13"
TOLERANCE"5%"
VALUE"0"
MATERIAL"CHIP"
PACK_TYPE"0402LF"
WATTAGE"1/16W"
$LOCATION"R4460"
CDS_LIB"pure_quanta"
CDS_LOCATION"R4460"
$SEC"1"
CDS_SEC"1";
"A"
$PN"1"27;
"B"
$PN"2"26;
%"Q_RES"
"2","(-1275,-2100)","0","pure_quanta","I19";
;
PART_NUMBER"CS00002JB13"
VALUE"0"
MATERIAL"CHIP"
$LOCATION"R4461"
WATTAGE"1/16W"
TOLERANCE"5%"
PACK_TYPE"0402LF"
CDS_LIB"pure_quanta"
CDS_LOCATION"R4461"
$SEC"1"
CDS_SEC"1";
"A"
$PN"1"24;
"B"
$PN"2"25;
%"Q_CAP"
"1","(-500,-2675)","0","pure_quanta","I2";
;
PART_NUMBER"CH4104K1B00"
VALUE"0.1UF"
MATERIAL"EMPTY"
TOLERANCE"10%"
VOLTAGE"25V"
PACK_TYPE"0402"
$LOCATION"C2321"
CDS_LIB"pure_quanta"
CDS_LOCATION"C2321"
$SEC"1"
CDS_SEC"1";
"B"
$PN"2"8;
"A"
$PN"1"31;
%"TUSB211IRWBR"
"1","(525,-2350)","0","pure_quanta","I20";
;
PART_NUMBER"AL000211007"
MATERIAL"EMPTY"
PART_TYPE"SMLF"
VALUE"TUSB211IRWBR"
$LOCATION"U312"
CDS_LIB"pure_quanta"
CDS_LMAN_SYM_OUTLINE"-225,175,225,-175"
NEEDS_NO_SIZE"TRUE"
CDS_LOCATION"U312"
$SEC"1"
CDS_SEC"1";
"GND"
$PN"10"16;
"EQ"
$PN"6"63;
"D2P"
$PN"7"61;
"D1P"
$PN"2"26;
"D1M"
$PN"1"25;
"CD"
$PN"4"66;
"ENA_HS"
$PN"9"55;
"VCC"
$PN"12"5;
"TEST"
$PN"3"67;
"VREG"
$PN"11"30;
"D2M"
$PN"8"56;
"RSTN"
$PN"5"31;
%"UNIVERSAL_POWER"
"1","(-1525,75)","2","logical_power","I21";
;
HDL_POWER"P3V3_AUX"
CDS_LIB"logical_power";
"A"3;
%"Q_RES"
"1","(-900,-575)","0","pure_quanta","I22";
;
PART_NUMBER"CS31002FB08"
MATERIAL"EMPTY"
PACK_TYPE"0402LF"
TOLERANCE"1%"
VALUE"10K"
WATTAGE"1/16W"
$LOCATION"R4459"
CDS_LIB"pure_quanta"
CDS_LOCATION"R4459"
$SEC"1"
CDS_SEC"1";
"B"
$PN"2"54;
"A"
$PN"1"3;
%"Q_RES"
"1","(-900,-450)","0","pure_quanta","I23";
;
PART_NUMBER"CS31002FB08"
VALUE"10K"
MATERIAL"EMPTY"
$LOCATION"R4458"
WATTAGE"1/16W"
TOLERANCE"1%"
PACK_TYPE"0402LF"
CDS_LIB"pure_quanta"
CDS_LOCATION"R4458"
$SEC"1"
CDS_SEC"1";
"B"
$PN"2"53;
"A"
$PN"1"3;
%"Q_RES"
"1","(-900,-325)","0","pure_quanta","I24";
;
PART_NUMBER"CS31002FB08"
MATERIAL"EMPTY"
VALUE"10K"
$LOCATION"R4457"
CDS_LIB"pure_quanta"
WATTAGE"1/16W"
TOLERANCE"1%"
PACK_TYPE"0402LF"
CDS_LOCATION"R4457"
$SEC"1"
CDS_SEC"1";
"B"
$PN"2"65;
"A"
$PN"1"3;
%"Q_RES"
"1","(-900,-175)","0","pure_quanta","I25";
;
PART_NUMBER"CS31002FB08"
VALUE"10K"
MATERIAL"EMPTY"
$LOCATION"R4456"
CDS_LIB"pure_quanta"
PACK_TYPE"0402LF"
TOLERANCE"1%"
WATTAGE"1/16W"
CDS_LOCATION"R4456"
$SEC"1"
CDS_SEC"1";
"B"
$PN"2"64;
"A"
$PN"1"3;
%"Q_RES"
"1","(-1250,650)","1","pure_quanta","I26";
;
PART_NUMBER"CS34702BB05"
PACK_TYPE"0402LF"
MATERIAL"EMPTY"
VALUE"47K"
TOLERANCE"0.1%"
WATTAGE"1/16W"
$LOCATION"R4453"
CDS_LIB"pure_quanta"
CDS_LOCATION"R4453"
$SEC"1"
CDS_SEC"1";
"B"
$PN"2"32;
"A"
$PN"1"11;
%"Q_RES"
"2","(-1250,1325)","0","pure_quanta","I27";
;
PART_NUMBER"CS31002FB08"
VALUE"10K"
TOLERANCE"1%"
PACK_TYPE"0402LF"
WATTAGE"1/16W"
MATERIAL"EMPTY"
$LOCATION"R4452"
CDS_LIB"pure_quanta"
CDS_LOCATION"R4452"
$SEC"1"
CDS_SEC"1";
"A"
$PN"1"2;
"B"
$PN"2"32;
%"UNIVERSAL_GND"
"1","(-25,-2900)","0","logical_power","I3";
;
CDS_LIB"logical_power"
HDL_POWER"GND";
"A"9;
%"UNIVERSAL_GND"
"1","(-100,350)","0","logical_power","I35";
;
CDS_LIB"logical_power"
HDL_POWER"GND";
"A"12;
%"UNIVERSAL_GND"
"1","(-425,375)","0","logical_power","I36";
;
CDS_LIB"logical_power"
HDL_POWER"GND";
"A"13;
%"Q_RES"
"2","(-425,650)","0","pure_quanta","I37";
;
PART_NUMBER"CS16802FB03"
PACK_TYPE"0402LF"
MATERIAL"EMPTY"
WATTAGE"1/16W"
TOLERANCE"1%"
VALUE"680"
$LOCATION"R4463"
CDS_LIB"pure_quanta"
CDS_LOCATION"R4463"
$SEC"1"
CDS_SEC"1";
"A"
$PN"1"34;
"B"
$PN"2"13;
%"Q_RES"
"2","(-100,625)","0","pure_quanta","I38";
;
PART_NUMBER"CS41002FB09"
PACK_TYPE"0402LF"
TOLERANCE"1%"
VALUE"100K"
MATERIAL"EMPTY"
WATTAGE"1/16W"
$LOCATION"R4464"
CDS_LIB"pure_quanta"
CDS_LOCATION"R4464"
$SEC"1"
CDS_SEC"1";
"A"
$PN"1"51;
"B"
$PN"2"12;
%"Q_RES"
"2","(-25,-2700)","0","pure_quanta","I4";
;
PART_NUMBER"CS23902JB04"
PACK_TYPE"0402LF"
MATERIAL"EMPTY"
TOLERANCE"5%"
WATTAGE"1/16W"
VALUE"3.9K"
$LOCATION"R4465"
CDS_LIB"pure_quanta"
CDS_LOCATION"R4465"
$SEC"1"
CDS_SEC"1";
"A"
$PN"1"63;
"B"
$PN"2"9;
%"GL852GOHY60"
"1","(775,1375)","0","pure_quanta","I40";
;
PART_NUMBER"AL000852001"
VALUE"GL852G-OHY60"
MATERIAL"EMPTY"
PART_TYPE"SMLF"
$LOCATION"U313"
NEEDS_NO_SIZE"TRUE"
CDS_LMAN_SYM_OUTLINE"-325,600,325,-600"
CDS_LIB"pure_quanta"
CDS_LOCATION"U313"
$SEC"1"
CDS_SEC"1";
"DM4"
$PN"15"69;
"DP4"
$PN"16"43;
"DM3"
$PN"12"70;
"DP3"
$PN"13"35;
"DM2"
$PN"6"36;
"DP2"
$PN"7"37;
"DM1"
$PN"3"38;
"DP1"
$PN"4"49;
"DM0"
$PN"1"46;
"DP0"
$PN"2"50;
"RREF"
$PN"8"34;
"PSELF"
$PN"22"71;
"PGANG"
$PN"23"51;
"RESET# \B"
$PN"17"32;
"OVCUR4# \B"
$PN"19"48;
"OVCUR3# \B"
$PN"20"47;
"OVCUR2#||SMD"
$PN"24"59;
"OVCUR1#||SMC"
$PN"25"52;
"TH"
$PN"TH"17;
"DVDD"
$PN"21"44;
"AVDD<2>"
$PN"14"45;
"AVDD<1>"
$PN"9"45;
"AVDD<0>"
$PN"5"45;
"V33"
$PN"28"45;
"V5"
$PN"27"45;
"SDA"
$PN"26"58;
"TEST||SCL"
$PN"18"57;
"X2"
$PN"11"39;
"X1"
$PN"10"40;
%"Q_RES"
"1","(-3100,2350)","0","pure_quanta","I41";
;
PART_NUMBER"CS00002JB13"
VALUE"0"
PACK_TYPE"0402LF"
MATERIAL"EMPTY"
$LOCATION"R4450"
CDS_LIB"pure_quanta"
WATTAGE"1/16W"
TOLERANCE"5%"
CDS_LOCATION"R4450"
$SEC"1"
CDS_SEC"1";
"B"
$PN"2"45;
"A"
$PN"1"4;
%"UNIVERSAL_GND"
"1","(-2800,1650)","0","logical_power","I42";
;
CDS_LIB"logical_power"
HDL_POWER"GND";
"A"14;
%"Q_CAP"
"1","(-2800,2050)","0","pure_quanta","I43";
;
PART_NUMBER"CH6101MEB01"
VOLTAGE"6.3V"
VALUE"10UF"
MATERIAL"EMPTY"
TOLERANCE"20%"
PACK_TYPE"C0402"
$LOCATION"C2313"
CDS_LIB"pure_quanta"
CDS_LOCATION"C2313"
$SEC"1"
CDS_SEC"1";
"B"
$PN"2"14;
"A"
$PN"1"45;
%"UNIVERSAL_POWER"
"1","(-3350,2500)","2","logical_power","I44";
;
HDL_POWER"P3V3_AUX"
CDS_LIB"logical_power";
"A"4;
%"Q_CAP"
"1","(-2425,2050)","2","pure_quanta","I45";
;
PART_NUMBER"CH4104K1B00"
TOLERANCE"10%"
VOLTAGE"25V"
VALUE"0.1UF"
MATERIAL"EMPTY"
PACK_TYPE"0402"
$LOCATION"C2314"
CDS_LIB"pure_quanta"
CDS_LOCATION"C2314"
$SEC"1"
CDS_SEC"1";
"B"
$PN"2"14;
"A"
$PN"1"45;
%"Q_CAP"
"1","(-2025,2050)","2","pure_quanta","I46";
;
PART_NUMBER"CH4104K1B00"
VOLTAGE"25V"
VALUE"0.1UF"
TOLERANCE"10%"
PACK_TYPE"0402"
MATERIAL"EMPTY"
$LOCATION"C2315"
CDS_LIB"pure_quanta"
CDS_LOCATION"C2315"
$SEC"1"
CDS_SEC"1";
"B"
$PN"2"14;
"A"
$PN"1"45;
%"Q_CAP"
"1","(-1650,2050)","0","pure_quanta","I47";
;
PART_NUMBER"CH5104KEB02"
VOLTAGE"25V"
VALUE"1UF"
TOLERANCE"10%"
MATERIAL"EMPTY"
PACK_TYPE"C0402"
$LOCATION"C2316"
CDS_LIB"pure_quanta"
CDS_LOCATION"C2316"
$SEC"1"
CDS_SEC"1";
"B"
$PN"2"14;
"A"
$PN"1"45;
%"UNIVERSAL_POWER"
"1","(-1250,1625)","2","logical_power","I48";
;
HDL_POWER"P3V3_AUX"
CDS_LIB"logical_power";
"A"2;
%"Q_CAP"
"1","(-1275,2050)","2","pure_quanta","I49";
;
PART_NUMBER"CH4104K1B00"
VOLTAGE"25V"
VALUE"0.1UF"
TOLERANCE"10%"
MATERIAL"EMPTY"
PACK_TYPE"0402"
$LOCATION"C2318"
CDS_LIB"pure_quanta"
CDS_LOCATION"C2318"
$SEC"1"
CDS_SEC"1";
"B"
$PN"2"14;
"A"
$PN"1"45;
%"Q_RES"
"1","(-450,1475)","0","pure_quanta","I50";
;
PART_NUMBER"CS00002JB13"
VALUE"0"
PACK_TYPE"0402LF"
MATERIAL"EMPTY"
$LOCATION"R4462"
WATTAGE"1/16W"
TOLERANCE"5%"
CDS_LIB"pure_quanta"
CDS_LOCATION"R4462"
$SEC"1"
CDS_SEC"1";
"B"
$PN"2"44;
"A"
$PN"1"45;
%"Q_CAP"
"1","(-900,2050)","2","pure_quanta","I51";
;
PART_NUMBER"CH4104K1B00"
VALUE"0.1UF"
VOLTAGE"25V"
PACK_TYPE"0402"
TOLERANCE"10%"
MATERIAL"EMPTY"
$LOCATION"C2319"
CDS_LIB"pure_quanta"
CDS_LOCATION"C2319"
$SEC"1"
CDS_SEC"1";
"B"
$PN"2"14;
"A"
$PN"1"45;
%"Q_CAP"
"1","(-525,2050)","2","pure_quanta","I52";
;
PART_NUMBER"CH4104K1B00"
VOLTAGE"25V"
VALUE"0.1UF"
TOLERANCE"10%"
PACK_TYPE"0402"
MATERIAL"EMPTY"
$LOCATION"C2320"
CDS_LIB"pure_quanta"
CDS_LOCATION"C2320"
$SEC"1"
CDS_SEC"1";
"B"
$PN"2"14;
"A"
$PN"1"45;
%"Q_CAP"
"1","(-175,2050)","0","pure_quanta","I53";
;
PART_NUMBER"CH5104KEB02"
PACK_TYPE"C0402"
MATERIAL"EMPTY"
TOLERANCE"10%"
VALUE"1UF"
VOLTAGE"25V"
$LOCATION"C2322"
CDS_LIB"pure_quanta"
CDS_LOCATION"C2322"
$SEC"1"
CDS_SEC"1";
"B"
$PN"2"14;
"A"
$PN"1"45;
%"UNIVERSAL_GND"
"1","(2125,-2875)","0","logical_power","I54";
;
CDS_LIB"logical_power"
HDL_POWER"GND";
"A"15;
%"Q_CAP"
"1","(2125,-2650)","0","pure_quanta","I55";
;
PART_NUMBER"CH4104K1B00"
MATERIAL"EMPTY"
TOLERANCE"10%"
VOLTAGE"25V"
VALUE"0.1UF"
PACK_TYPE"0402"
$LOCATION"C2325"
CDS_LIB"pure_quanta"
CDS_LOCATION"C2325"
$SEC"1"
CDS_SEC"1";
"B"
$PN"2"15;
"A"
$PN"1"30;
%"Q_CAP"
"1","(925,-1725)","0","pure_quanta","I56";
;
PART_NUMBER"CH5104KEB02"
MATERIAL"EMPTY"
PACK_TYPE"C0402"
VALUE"1UF"
VOLTAGE"25V"
TOLERANCE"10%"
$LOCATION"C2323"
CDS_LIB"pure_quanta"
CDS_LOCATION"C2323"
$SEC"1"
CDS_SEC"1";
"B"
$PN"2"23;
"A"
$PN"1"5;
%"UNIVERSAL_GND"
"1","(1375,-2075)","0","logical_power","I57";
;
CDS_LIB"logical_power"
HDL_POWER"GND";
"A"23;
%"Q_CAP"
"1","(1375,-1725)","0","pure_quanta","I58";
;
PART_NUMBER"CH4104K1B00"
VALUE"0.1UF"
VOLTAGE"25V"
TOLERANCE"10%"
MATERIAL"EMPTY"
PACK_TYPE"0402"
$LOCATION"C2324"
CDS_LIB"pure_quanta"
CDS_LOCATION"C2324"
$SEC"1"
CDS_SEC"1";
"B"
$PN"2"23;
"A"
$PN"1"5;
%"UNIVERSAL_GND"
"1","(2025,-2600)","0","logical_power","I59";
;
CDS_LIB"logical_power"
HDL_POWER"GND";
"A"16;
%"Q_RES"
"1","(2250,-2275)","0","pure_quanta","I60";
;
PART_NUMBER"CS00002JB13"
PACK_TYPE"0402LF"
MATERIAL"CHIP"
VALUE"0"
$LOCATION"R4468"
WATTAGE"1/16W"
TOLERANCE"5%"
CDS_LIB"pure_quanta"
CDS_LOCATION"R4468"
$SEC"1"
CDS_SEC"1";
"B"
$PN"2"62;
"A"
$PN"1"56;
%"Q_RES"
"1","(2250,-2225)","0","pure_quanta","I61";
;
PART_NUMBER"CS00002JB13"
PACK_TYPE"0402LF"
VALUE"0"
MATERIAL"CHIP"
$LOCATION"R4467"
WATTAGE"1/16W"
TOLERANCE"5%"
CDS_LIB"pure_quanta"
CDS_LOCATION"R4467"
$SEC"1"
CDS_SEC"1";
"B"
$PN"2"60;
"A"
$PN"1"61;
%"UNIVERSAL_POWER"
"1","(1800,-1400)","2","logical_power","I62";
;
HDL_POWER"P3V3_AUX"
CDS_LIB"logical_power";
"A"5;
%"UNIVERSAL_GND"
"1","(1375,675)","0","logical_power","I63";
;
CDS_LIB"logical_power"
HDL_POWER"GND";
"A"17;
%"UNIVERSAL_GND"
"1","(-3500,-525)","0","logical_power","I7";
;
CDS_LIB"logical_power"
HDL_POWER"GND";
"A"10;
%"Q_RES"
"2","(3475,1200)","0","pure_quanta","I72";
;
PART_NUMBER"CS00002JB13"
PACK_TYPE"0402LF"
WATTAGE"1/16W"
MATERIAL"CHIP"
TOLERANCE"5%"
VALUE"0"
$LOCATION"R4474"
CDS_LIB"pure_quanta"
CDS_LOCATION"R4474"
$SEC"1"
CDS_SEC"1";
"A"
$PN"1"42;
"B"
$PN"2"24;
%"Q_RES"
"2","(3375,1200)","0","pure_quanta","I73";
;
PART_NUMBER"CS00002JB13"
MATERIAL"CHIP"
VALUE"0"
$LOCATION"R4473"
WATTAGE"1/16W"
TOLERANCE"5%"
PACK_TYPE"0402LF"
CDS_LIB"pure_quanta"
CDS_LOCATION"R4473"
$SEC"1"
CDS_SEC"1";
"A"
$PN"1"41;
"B"
$PN"2"27;
%"Q_RES"
"1","(2125,1825)","0","pure_quanta","I75";
;
PART_NUMBER"CS00002JB13"
PACK_TYPE"0402LF"
MATERIAL"EMPTY"
VALUE"0"
$LOCATION"R4466"
WATTAGE"1/16W"
TOLERANCE"5%"
CDS_LIB"pure_quanta"
CDS_LOCATION"R4466"
$SEC"1"
CDS_SEC"1";
"B"
$PN"2"18;
"A"
$PN"1"57;
%"UNIVERSAL_GND"
"1","(2675,1825)","1","logical_power","I76";
;
CDS_LIB"logical_power"
HDL_POWER"GND";
"A"18;
%"Q_RES"
"1","(3200,1475)","0","pure_quanta","I77";
;
PART_NUMBER"CS00002JB13"
PACK_TYPE"0402LF"
VALUE"0"
MATERIAL"EMPTY"
$LOCATION"R4471"
WATTAGE"1/16W"
TOLERANCE"5%"
CDS_LIB"pure_quanta"
CDS_LOCATION"R4471"
$SEC"1"
CDS_SEC"1";
"B"
$PN"2"41;
"A"
$PN"1"50;
%"Q_RES"
"1","(3200,1425)","0","pure_quanta","I78";
;
PART_NUMBER"CS00002JB13"
MATERIAL"EMPTY"
VALUE"0"
PACK_TYPE"0402LF"
$LOCATION"R4472"
TOLERANCE"5%"
WATTAGE"1/16W"
CDS_LIB"pure_quanta"
CDS_LOCATION"R4472"
$SEC"1"
CDS_SEC"1";
"B"
$PN"2"42;
"A"
$PN"1"46;
%"Q_RES"
"2","(-3500,-100)","0","pure_quanta","I8";
;
PART_NUMBER"CS31002FB08"
PACK_TYPE"0402LF"
MATERIAL"EMPTY"
TOLERANCE"1%"
VALUE"10K"
WATTAGE"1/16W"
$LOCATION"R4449"
CDS_LIB"pure_quanta"
CDS_LOCATION"R4449"
$SEC"1"
CDS_SEC"1";
"A"
$PN"1"29;
"B"
$PN"2"10;
%"UNIVERSAL_GND"
"1","(4125,1700)","0","logical_power","I80";
;
CDS_LIB"logical_power"
HDL_POWER"GND";
"A"19;
%"Q_CAP"
"1","(4125,1925)","0","pure_quanta","I81";
;
PART_NUMBER"CH01206JB05"
TOLERANCE"5%"
VALUE"12PF"
VOLTAGE"50V"
MATERIAL"EMPTY"
PACK_TYPE"C0402"
$LOCATION"C2326"
CDS_LIB"pure_quanta"
CDS_LOCATION"C2326"
$SEC"1"
CDS_SEC"1";
"B"
$PN"2"19;
"A"
$PN"1"40;
%"UNIVERSAL_GND"
"1","(4350,1875)","0","logical_power","I82";
;
CDS_LIB"logical_power"
HDL_POWER"GND";
"A"20;
%"Q_XTAL_4P_13BI_24GND"
"1","(4675,2100)","0","pure_quanta","I83";
;
PART_NUMBER"BG6120000E0"
MATERIAL"EMPTY"
VALUE"12MHZ"
PART_TYPE"SMLF"
$LOCATION"Y9"
CDS_LIB"pure_quanta"
PIN_NAMES_ROTATE"True"
CDS_LMAN_SYM_OUTLINE"-125,175,125,-175"
CDS_LOCATION"Y9"
$SEC"1"
CDS_SEC"1";
"X2"
$PN"3"39;
"G2"
$PN"4"21;
"G1"
$PN"2"20;
"X1"
$PN"1"40;
%"UNIVERSAL_GND"
"1","(5000,1875)","0","logical_power","I84";
;
CDS_LIB"logical_power"
HDL_POWER"GND";
"A"21;
%"Q_CAP"
"1","(5125,1925)","0","pure_quanta","I85";
;
PART_NUMBER"CH01206JB05"
PACK_TYPE"C0402"
MATERIAL"EMPTY"
TOLERANCE"5%"
VALUE"12PF"
VOLTAGE"50V"
$LOCATION"C2327"
CDS_LIB"pure_quanta"
CDS_LOCATION"C2327"
$SEC"1"
CDS_SEC"1";
"B"
$PN"2"22;
"A"
$PN"1"39;
%"UNIVERSAL_GND"
"1","(5125,1700)","0","logical_power","I86";
;
CDS_LIB"logical_power"
HDL_POWER"GND";
"A"22;
%"Q_RES"
"2","(-1575,-1475)","0","pure_quanta","I88";
;
PART_NUMBER"CS04992FB07"
VALUE"49.9"
MATERIAL"EMPTY"
$LOCATION"R4487"
WATTAGE"1/16W"
TOLERANCE"1%"
PACK_TYPE"0402LF"
CDS_LIB"pure_quanta"
CDS_LOCATION"R4487"
$SEC"1"
CDS_SEC"1";
"A"
$PN"1"24;
"B"
$PN"2"6;
%"UNIVERSAL_GND"
"1","(-1575,-1700)","0","logical_power","I89";
;
CDS_LIB"logical_power"
HDL_POWER"GND"
ROOM"IO_SLOT";
"A"6;
%"Q_RES"
"2","(-3500,500)","0","pure_quanta","I9";
;
PART_NUMBER"CS31002FB08"
PACK_TYPE"0402LF"
VALUE"10K"
TOLERANCE"1%"
WATTAGE"1/16W"
MATERIAL"EMPTY"
$LOCATION"R4448"
CDS_LIB"pure_quanta"
CDS_LOCATION"R4448"
$SEC"1"
CDS_SEC"1";
"A"
$PN"1"1;
"B"
$PN"2"29;
%"Q_RES"
"2","(-1750,-1475)","0","pure_quanta","I90";
;
PART_NUMBER"CS04992FB07"
MATERIAL"EMPTY"
VALUE"49.9"
$LOCATION"R4486"
PACK_TYPE"0402LF"
TOLERANCE"1%"
WATTAGE"1/16W"
CDS_LIB"pure_quanta"
CDS_LOCATION"R4486"
$SEC"1"
CDS_SEC"1";
"A"
$PN"1"27;
"B"
$PN"2"7;
%"UNIVERSAL_GND"
"1","(-1750,-1700)","0","logical_power","I91";
;
CDS_LIB"logical_power"
HDL_POWER"GND"
ROOM"IO_SLOT";
"A"7;
END.
